(kicad_pcb
	(version 20241229)
	(generator "pcbnew")
	(generator_version "9.0")
	(general
		(thickness 1.62)
		(legacy_teardrops no)
	)
	(paper "A4")
	(title_block
		(title "OCuLink to 10GbE adapter")
		(date "2026-02-23")
		(rev "1.1.0")
		(company "Antmicro Ltd")
		(comment 1 "www.antmicro.com")
		(comment 9 "footprints 368-372 of 510")
	)
	(layers
		(0 "F.Cu" signal)
		(4 "In1.Cu" signal)
		(6 "In2.Cu" signal)
		(8 "In3.Cu" signal)
		(10 "In4.Cu" signal)
		(12 "In5.Cu" signal)
		(14 "In6.Cu" signal)
		(2 "B.Cu" signal)
		(9 "F.Adhes" user "F.Adhesive")
		(11 "B.Adhes" user "B.Adhesive")
		(13 "F.Paste" user)
		(15 "B.Paste" user)
		(5 "F.SilkS" user "F.Silkscreen")
		(7 "B.SilkS" user "B.Silkscreen")
		(1 "F.Mask" user)
		(3 "B.Mask" user)
		(17 "Dwgs.User" user "User.Drawings")
		(19 "Cmts.User" user "User.Comments")
		(21 "Eco1.User" user "User.Eco1")
		(23 "Eco2.User" user "User.Eco2")
		(25 "Edge.Cuts" user)
		(27 "Margin" user)
		(31 "F.CrtYd" user "F.Courtyard")
		(29 "B.CrtYd" user "B.Courtyard")
		(35 "F.Fab" user)
		(33 "B.Fab" user)
	)
	(footprint "antmicro-footprints:C_0402_1005Metric"
		(layer "B.Cu")
		(at 75.479998 145.34 -90)
		(descr "Capacitor SMD 0402")
		(tags "capacitor SMD 0402")
		(property "Reference" "C48"
			(at -2.94 -0.490002 90)
			(layer "B.SilkS")
			(effects
				(font
					(size 0.7 0.7)
					(thickness 0.15)
				)
				(justify left bottom mirror)
			)
		)
		(property "Value" "C_470p_0402"
			(at -1.022927 -2.155213 90)
			(layer "B.Fab")
			(hide yes)
			(effects
				(font
					(size 0.7 0.7)
					(thickness 0.15)
				)
				(justify left bottom mirror)
			)
		)
		(property "Datasheet" "https://www.passivecomponent.com/wp-content/uploads/datasheet/WTC_MLCC_General_Purpose.pdf"
			(at 0 0 90)
			(layer "B.Fab")
			(hide yes)
			(effects
				(font
					(size 1.27 1.27)
					(thickness 0.15)
				)
				(justify mirror)
			)
		)
		(property "Description" "SMD Multilayer Ceramic Capacitor, General Purpose, 470 pF, 25 V, 0402 [1005 Metric], ± 10%, X7R"
			(at 0 0 90)
			(layer "B.Fab")
			(hide yes)
			(effects
				(font
					(size 1.27 1.27)
					(thickness 0.15)
				)
				(justify mirror)
			)
		)
		(property "MPN" "0402B471K250CT"
			(at 0 0 270)
			(unlocked yes)
			(layer "B.Fab")
			(hide yes)
			(effects
				(font
					(size 1 1)
					(thickness 0.15)
				)
				(justify mirror)
			)
		)
		(property "Manufacturer" "Walsin"
			(at 0 0 270)
			(unlocked yes)
			(layer "B.Fab")
			(hide yes)
			(effects
				(font
					(size 1 1)
					(thickness 0.15)
				)
				(justify mirror)
			)
		)
		(property "License" "Apache-2.0"
			(at 0 0 270)
			(unlocked yes)
			(layer "B.Fab")
			(hide yes)
			(effects
				(font
					(size 1 1)
					(thickness 0.15)
				)
				(justify mirror)
			)
		)
		(property "Author" "Antmicro"
			(at 0 0 270)
			(unlocked yes)
			(layer "B.Fab")
			(hide yes)
			(effects
				(font
					(size 1 1)
					(thickness 0.15)
				)
				(justify mirror)
			)
		)
		(property "Val" "470p"
			(at 0 0 270)
			(unlocked yes)
			(layer "B.Fab")
			(hide yes)
			(effects
				(font
					(size 1 1)
					(thickness 0.15)
				)
				(justify mirror)
			)
		)
		(property "Voltage" "25V"
			(at 0 0 270)
			(unlocked yes)
			(layer "B.Fab")
			(hide yes)
			(effects
				(font
					(size 1 1)
					(thickness 0.15)
				)
				(justify mirror)
			)
		)
		(property "Dielectric" "X7R"
			(at 0 0 270)
			(unlocked yes)
			(layer "B.Fab")
			(hide yes)
			(effects
				(font
					(size 1 1)
					(thickness 0.15)
				)
				(justify mirror)
			)
		)
		(sheetname "/2xRJ45/")
		(sheetfile "2xrj45.kicad_sch")
		(attr smd)
		(fp_rect
			(start -0.925 0.47)
			(end 0.925 -0.47)
			(stroke
				(width 0.05)
				(type default)
			)
			(fill no)
			(layer "B.CrtYd")
		)
		(fp_line
			(start -0.494 0.25)
			(end 0.504 0.25)
			(stroke
				(width 0.15)
				(type solid)
			)
			(layer "B.Fab")
		)
		(fp_line
			(start 0.504 0.25)
			(end 0.504 -0.248)
			(stroke
				(width 0.15)
				(type solid)
			)
			(layer "B.Fab")
		)
		(fp_line
			(start -0.494 -0.248)
			(end -0.494 0.25)
			(stroke
				(width 0.15)
				(type solid)
			)
			(layer "B.Fab")
		)
		(fp_line
			(start 0.504 -0.248)
			(end -0.494 -0.248)
			(stroke
				(width 0.15)
				(type solid)
			)
			(layer "B.Fab")
		)
		(pad "1" smd roundrect
			(at -0.48 0 270)
			(size 0.59 0.64)
			(layers "B.Cu" "B.Mask" "B.Paste")
			(roundrect_rratio 0.25)
			(net 28 "GND")
			(pintype "passive")
		)
		(pad "2" smd roundrect
			(at 0.48 0 270)
			(size 0.59 0.64)
			(layers "B.Cu" "B.Mask" "B.Paste")
			(roundrect_rratio 0.25)
			(net 52 "Net-(J3-LED_YG_Y-)")
			(pintype "passive")
		)
	)
	(footprint "antmicro-footprints:C_0402_1005Metric"
		(layer "B.Cu")
		(at 81.95 132.4 180)
		(descr "Capacitor SMD 0402")
		(tags "capacitor SMD 0402")
		(property "Reference" "C58"
			(at -0.721 -3.350999 0)
			(layer "B.SilkS")
			(effects
				(font
					(size 0.7 0.7)
					(thickness 0.15)
				)
				(justify left bottom mirror)
			)
		)
		(property "Value" "C_1u_25V_0402"
			(at -1.022927 -2.155213 0)
			(layer "B.Fab")
			(hide yes)
			(effects
				(font
					(size 0.7 0.7)
					(thickness 0.15)
				)
				(justify left bottom mirror)
			)
		)
		(property "Datasheet" "https://www.murata.com/products/productdetail?partno=GRM155R61E105KE11%23"
			(at 0 0 0)
			(layer "B.Fab")
			(hide yes)
			(effects
				(font
					(size 1.27 1.27)
					(thickness 0.15)
				)
				(justify mirror)
			)
		)
		(property "Description" "SMD Multilayer Ceramic Capacitor, 1 µF, 25 V, 0402 [1005 Metric], ± 10%, X5R, GRM Series"
			(at 0 0 0)
			(layer "B.Fab")
			(hide yes)
			(effects
				(font
					(size 1.27 1.27)
					(thickness 0.15)
				)
				(justify mirror)
			)
		)
		(property "MPN" "GRM155R61E105KE11J"
			(at 0 0 180)
			(unlocked yes)
			(layer "B.Fab")
			(hide yes)
			(effects
				(font
					(size 1 1)
					(thickness 0.15)
				)
				(justify mirror)
			)
		)
		(property "Manufacturer" "Murata"
			(at 0 0 180)
			(unlocked yes)
			(layer "B.Fab")
			(hide yes)
			(effects
				(font
					(size 1 1)
					(thickness 0.15)
				)
				(justify mirror)
			)
		)
		(property "License" "Apache-2.0"
			(at 0 0 180)
			(unlocked yes)
			(layer "B.Fab")
			(hide yes)
			(effects
				(font
					(size 1 1)
					(thickness 0.15)
				)
				(justify mirror)
			)
		)
		(property "Author" "Antmicro"
			(at 0 0 180)
			(unlocked yes)
			(layer "B.Fab")
			(hide yes)
			(effects
				(font
					(size 1 1)
					(thickness 0.15)
				)
				(justify mirror)
			)
		)
		(property "Val" "1u"
			(at 0 0 180)
			(unlocked yes)
			(layer "B.Fab")
			(hide yes)
			(effects
				(font
					(size 1 1)
					(thickness 0.15)
				)
				(justify mirror)
			)
		)
		(property "Voltage" "25V"
			(at 0 0 180)
			(unlocked yes)
			(layer "B.Fab")
			(hide yes)
			(effects
				(font
					(size 1 1)
					(thickness 0.15)
				)
				(justify mirror)
			)
		)
		(property "Dielectric" "X5R"
			(at 0 0 180)
			(unlocked yes)
			(layer "B.Fab")
			(hide yes)
			(effects
				(font
					(size 1 1)
					(thickness 0.15)
				)
				(justify mirror)
			)
		)
		(sheetname "/2xRJ45/")
		(sheetfile "2xrj45.kicad_sch")
		(attr smd)
		(fp_rect
			(start -0.925 0.47)
			(end 0.925 -0.47)
			(stroke
				(width 0.05)
				(type default)
			)
			(fill no)
			(layer "B.CrtYd")
		)
		(fp_line
			(start 0.504 0.25)
			(end 0.504 -0.248)
			(stroke
				(width 0.15)
				(type solid)
			)
			(layer "B.Fab")
		)
		(fp_line
			(start 0.504 -0.248)
			(end -0.494 -0.248)
			(stroke
				(width 0.15)
				(type solid)
			)
			(layer "B.Fab")
		)
		(fp_line
			(start -0.494 0.25)
			(end 0.504 0.25)
			(stroke
				(width 0.15)
				(type solid)
			)
			(layer "B.Fab")
		)
		(fp_line
			(start -0.494 -0.248)
			(end -0.494 0.25)
			(stroke
				(width 0.15)
				(type solid)
			)
			(layer "B.Fab")
		)
		(pad "1" smd roundrect
			(at -0.48 0 180)
			(size 0.59 0.64)
			(layers "B.Cu" "B.Mask" "B.Paste")
			(roundrect_rratio 0.25)
			(net 28 "GND")
			(pintype "passive")
		)
		(pad "2" smd roundrect
			(at 0.48 0 180)
			(size 0.59 0.64)
			(layers "B.Cu" "B.Mask" "B.Paste")
			(roundrect_rratio 0.25)
			(net 299 "/2xRJ45/P0_CT")
			(pintype "passive")
		)
	)
	(footprint "antmicro-footprints:C_0402_1005Metric"
		(layer "B.Cu")
		(at 88.225 102 90)
		(descr "Capacitor SMD 0402")
		(tags "capacitor SMD 0402")
		(property "Reference" "C89"
			(at 9.09 -0.447343 90)
			(layer "B.SilkS")
			(effects
				(font
					(size 0.7 0.7)
					(thickness 0.15)
				)
				(justify right top mirror)
			)
		)
		(property "Value" "C_1u_25V_0402"
			(at -1.022927 -2.155213 90)
			(layer "B.Fab")
			(hide yes)
			(effects
				(font
					(size 0.7 0.7)
					(thickness 0.15)
				)
				(justify right top mirror)
			)
		)
		(property "Datasheet" "https://www.murata.com/products/productdetail?partno=GRM155R61E105KE11%23"
			(at 0 0 90)
			(layer "B.Fab")
			(hide yes)
			(effects
				(font
					(size 1.27 1.27)
					(thickness 0.15)
				)
				(justify mirror)
			)
		)
		(property "Description" "SMD Multilayer Ceramic Capacitor, 1 µF, 25 V, 0402 [1005 Metric], ± 10%, X5R, GRM Series"
			(at 0 0 90)
			(layer "B.Fab")
			(hide yes)
			(effects
				(font
					(size 1.27 1.27)
					(thickness 0.15)
				)
				(justify mirror)
			)
		)
		(property "MPN" "GRM155R61E105KE11J"
			(at 0 0 90)
			(unlocked yes)
			(layer "B.Fab")
			(hide yes)
			(effects
				(font
					(size 1 1)
					(thickness 0.15)
				)
				(justify mirror)
			)
		)
		(property "Manufacturer" "Murata"
			(at 0 0 90)
			(unlocked yes)
			(layer "B.Fab")
			(hide yes)
			(effects
				(font
					(size 1 1)
					(thickness 0.15)
				)
				(justify mirror)
			)
		)
		(property "License" "Apache-2.0"
			(at 0 0 90)
			(unlocked yes)
			(layer "B.Fab")
			(hide yes)
			(effects
				(font
					(size 1 1)
					(thickness 0.15)
				)
				(justify mirror)
			)
		)
		(property "Author" "Antmicro"
			(at 0 0 90)
			(unlocked yes)
			(layer "B.Fab")
			(hide yes)
			(effects
				(font
					(size 1 1)
					(thickness 0.15)
				)
				(justify mirror)
			)
		)
		(property "Val" "1u"
			(at 0 0 90)
			(unlocked yes)
			(layer "B.Fab")
			(hide yes)
			(effects
				(font
					(size 1 1)
					(thickness 0.15)
				)
				(justify mirror)
			)
		)
		(property "Voltage" "25V"
			(at 0 0 90)
			(unlocked yes)
			(layer "B.Fab")
			(hide yes)
			(effects
				(font
					(size 1 1)
					(thickness 0.15)
				)
				(justify mirror)
			)
		)
		(property "Dielectric" "X5R"
			(at 0 0 90)
			(unlocked yes)
			(layer "B.Fab")
			(hide yes)
			(effects
				(font
					(size 1 1)
					(thickness 0.15)
				)
				(justify mirror)
			)
		)
		(sheetname "/X710-AT2 power/")
		(sheetfile "x710-at2-power.kicad_sch")
		(attr smd)
		(fp_rect
			(start -0.925 0.47)
			(end 0.925 -0.47)
			(stroke
				(width 0.05)
				(type default)
			)
			(fill no)
			(layer "B.CrtYd")
		)
		(fp_line
			(start 0.504 -0.248)
			(end -0.494 -0.248)
			(stroke
				(width 0.15)
				(type solid)
			)
			(layer "B.Fab")
		)
		(fp_line
			(start -0.494 -0.248)
			(end -0.494 0.25)
			(stroke
				(width 0.15)
				(type solid)
			)
			(layer "B.Fab")
		)
		(fp_line
			(start 0.504 0.25)
			(end 0.504 -0.248)
			(stroke
				(width 0.15)
				(type solid)
			)
			(layer "B.Fab")
		)
		(fp_line
			(start -0.494 0.25)
			(end 0.504 0.25)
			(stroke
				(width 0.15)
				(type solid)
			)
			(layer "B.Fab")
		)
		(pad "1" smd roundrect
			(at -0.48 0 90)
			(size 0.59 0.64)
			(layers "B.Cu" "B.Mask" "B.Paste")
			(roundrect_rratio 0.25)
			(net 28 "GND")
			(pintype "passive")
		)
		(pad "2" smd roundrect
			(at 0.48 0 90)
			(size 0.59 0.64)
			(layers "B.Cu" "B.Mask" "B.Paste")
			(roundrect_rratio 0.25)
			(net 1 "VCCA")
			(pintype "passive")
		)
	)
	(footprint "antmicro-footprints:R_0402_1005Metric"
		(layer "B.Cu")
		(at 96.45 105.1 180)
		(descr "Resistor SMD 0402")
		(tags "resistor SMD 0402")
		(property "Reference" "R86"
			(at -0.9 0.272222 0)
			(layer "B.SilkS")
			(effects
				(font
					(size 0.7 0.7)
					(thickness 0.15)
				)
				(justify right top mirror)
			)
		)
		(property "Value" "R_22R_0402"
			(at -1.011843 -1.772047 0)
			(layer "B.Fab")
			(hide yes)
			(effects
				(font
					(size 0.7 0.7)
					(thickness 0.15)
				)
				(justify left bottom mirror)
			)
		)
		(property "Datasheet" "https://www.bourns.com/docs/product-datasheets/cr.pdf"
			(at 0 0 0)
			(layer "B.Fab")
			(hide yes)
			(effects
				(font
					(size 1.27 1.27)
					(thickness 0.15)
				)
				(justify mirror)
			)
		)
		(property "Description" "SMD Chip Resistor, 22 ohm, ± 1%, 62.5 mW, 0402 [1005 Metric], Thick Film, General Purpose"
			(at 0 0 0)
			(layer "B.Fab")
			(hide yes)
			(effects
				(font
					(size 1.27 1.27)
					(thickness 0.15)
				)
				(justify mirror)
			)
		)
		(property "MPN" "CR0402-FX-22R0GLF"
			(at 0 0 180)
			(unlocked yes)
			(layer "B.Fab")
			(hide yes)
			(effects
				(font
					(size 1 1)
					(thickness 0.15)
				)
				(justify mirror)
			)
		)
		(property "Manufacturer" "Bourns"
			(at 0 0 180)
			(unlocked yes)
			(layer "B.Fab")
			(hide yes)
			(effects
				(font
					(size 1 1)
					(thickness 0.15)
				)
				(justify mirror)
			)
		)
		(property "License" "Apache-2.0"
			(at 0 0 180)
			(unlocked yes)
			(layer "B.Fab")
			(hide yes)
			(effects
				(font
					(size 1 1)
					(thickness 0.15)
				)
				(justify mirror)
			)
		)
		(property "Author" "Antmicro"
			(at 0 0 180)
			(unlocked yes)
			(layer "B.Fab")
			(hide yes)
			(effects
				(font
					(size 1 1)
					(thickness 0.15)
				)
				(justify mirror)
			)
		)
		(property "Val" "22R"
			(at 0 0 180)
			(unlocked yes)
			(layer "B.Fab")
			(hide yes)
			(effects
				(font
					(size 1 1)
					(thickness 0.15)
				)
				(justify mirror)
			)
		)
		(property "Tolerance" "1%"
			(at 0 0 180)
			(unlocked yes)
			(layer "B.Fab")
			(hide yes)
			(effects
				(font
					(size 1 1)
					(thickness 0.15)
				)
				(justify mirror)
			)
		)
		(sheetname "/X710-AT2 Misc/")
		(sheetfile "x710-at2-mics.kicad_sch")
		(attr smd)
		(fp_rect
			(start -0.925 0.47)
			(end 0.925 -0.47)
			(stroke
				(width 0.05)
				(type default)
			)
			(fill no)
			(layer "B.CrtYd")
		)
		(fp_rect
			(start -0.5 0.25)
			(end 0.5 -0.25)
			(stroke
				(width 0.15)
				(type solid)
			)
			(fill no)
			(layer "B.Fab")
		)
		(pad "1" smd roundrect
			(at -0.48 0 180)
			(size 0.59 0.64)
			(layers "B.Cu" "B.Mask" "B.Paste")
			(roundrect_rratio 0.25)
			(net 360 "/X710-AT2 Misc/NCSI.RXD_1")
			(pintype "passive")
		)
		(pad "2" smd roundrect
			(at 0.48 0 180)
			(size 0.59 0.64)
			(layers "B.Cu" "B.Mask" "B.Paste")
			(roundrect_rratio 0.25)
			(net 162 "Net-(U9D-NCSI_RXD_1)")
			(pintype "passive")
		)
	)
	(footprint "antmicro-footprints:R_0402_1005Metric"
		(layer "B.Cu")
		(at 84.225 98.3 -90)
		(descr "Resistor SMD 0402")
		(tags "resistor SMD 0402")
		(property "Reference" "R139"
			(at -13.44 -0.297657 90)
			(layer "B.SilkS")
			(effects
				(font
					(size 0.7 0.7)
					(thickness 0.15)
				)
				(justify left bottom mirror)
			)
		)
		(property "Value" "R_100R_0402"
			(at -1.011843 -1.772046 90)
			(layer "B.Fab")
			(hide yes)
			(effects
				(font
					(size 0.7 0.7)
					(thickness 0.15)
				)
				(justify left bottom mirror)
			)
		)
		(property "Datasheet" "https://www.bourns.com/docs/product-datasheets/cr.pdf"
			(at 0 0 90)
			(layer "B.Fab")
			(hide yes)
			(effects
				(font
					(size 1.27 1.27)
					(thickness 0.15)
				)
				(justify mirror)
			)
		)
		(property "Description" "SMD Chip Resistor, 100 ohm, ± 1%, 62.5 mW, 0402 [1005 Metric], Thick Film, General Purpose"
			(at 0 0 90)
			(layer "B.Fab")
			(hide yes)
			(effects
				(font
					(size 1.27 1.27)
					(thickness 0.15)
				)
				(justify mirror)
			)
		)
		(property "MPN" "CR0402-FX-1000GLF"
			(at 0 0 270)
			(unlocked yes)
			(layer "B.Fab")
			(hide yes)
			(effects
				(font
					(size 1 1)
					(thickness 0.15)
				)
				(justify mirror)
			)
		)
		(property "Manufacturer" "Bourns"
			(at 0 0 270)
			(unlocked yes)
			(layer "B.Fab")
			(hide yes)
			(effects
				(font
					(size 1 1)
					(thickness 0.15)
				)
				(justify mirror)
			)
		)
		(property "License" "Apache-2.0"
			(at 0 0 270)
			(unlocked yes)
			(layer "B.Fab")
			(hide yes)
			(effects
				(font
					(size 1 1)
					(thickness 0.15)
				)
				(justify mirror)
			)
		)
		(property "Author" "Antmicro"
			(at 0 0 270)
			(unlocked yes)
			(layer "B.Fab")
			(hide yes)
			(effects
				(font
					(size 1 1)
					(thickness 0.15)
				)
				(justify mirror)
			)
		)
		(property "Val" "100R"
			(at 0 0 270)
			(unlocked yes)
			(layer "B.Fab")
			(hide yes)
			(effects
				(font
					(size 1 1)
					(thickness 0.15)
				)
				(justify mirror)
			)
		)
		(property "Tolerance" "1%"
			(at 0 0 270)
			(unlocked yes)
			(layer "B.Fab")
			(hide yes)
			(effects
				(font
					(size 1 1)
					(thickness 0.15)
				)
				(justify mirror)
			)
		)
		(sheetname "/X710-AT2 RSVD/")
		(sheetfile "x710-at2-rsvd.kicad_sch")
		(attr smd)
		(fp_rect
			(start -0.925 0.47)
			(end 0.925 -0.47)
			(stroke
				(width 0.05)
				(type default)
			)
			(fill no)
			(layer "B.CrtYd")
		)
		(fp_rect
			(start -0.5 0.25)
			(end 0.5 -0.25)
			(stroke
				(width 0.15)
				(type solid)
			)
			(fill no)
			(layer "B.Fab")
		)
		(pad "1" smd roundrect
			(at -0.48 0 270)
			(size 0.59 0.64)
			(layers "B.Cu" "B.Mask" "B.Paste")
			(roundrect_rratio 0.25)
			(net 28 "GND")
			(pintype "passive")
		)
		(pad "2" smd roundrect
			(at 0.48 0 270)
			(size 0.59 0.64)
			(layers "B.Cu" "B.Mask" "B.Paste")
			(roundrect_rratio 0.25)
			(net 127 "/X710-AT2 RSVD/RSVDP22_VSS")
			(pintype "passive")
		)
	)
)
